# BASEBOARD_FAB2 (Tioga Pass) — schematic netlist excerpt (pin names and nets, part order shuffled) for the footprints in the layout excerpt that follows; sources: Cadence DE-HDL packaged netlist, KiCad conversion of Wiwynn_Tioga_Pass_MB.brd

J6L1  SCONN288_H44441003  SCONN  pkg PIP  page 54
  \12v\(1)  = P12V_NVDIMM_DEF
  VSS(93)  = GND
  DQ(4)  = M_F_DQ<4>
  VSS(92)  = GND
  DQ(0)  = M_F_DQ<0>
  VSS(91)  = GND
  DQS9P  = M_F_DQS_DP<9>
  DQS9N  = M_F_DQS_DN<9>
  VSS(90)  = GND
  DQ(6)  = M_F_DQ<6>
  VSS(89)  = GND
  DQ(2)  = M_F_DQ<2>
  VSS(88)  = GND
  DQ(12)  = M_F_DQ<12>
  VSS(87)  = GND
  DQ(8)  = M_F_DQ<8>
  VSS(86)  = GND
  DQS10P  = M_F_DQS_DP<10>
  DQS10N  = M_F_DQS_DN<10>
  VSS(85)  = GND
  DQ(14)  = M_F_DQ<14>
  VSS(84)  = GND
  DQ(10)  = M_F_DQ<10>
  VSS(83)  = GND
  DQ(20)  = M_F_DQ<20>
  VSS(82)  = GND
  DQ(16)  = M_F_DQ<16>
  VSS(81)  = GND
  DQS11P  = M_F_DQS_DP<11>
  DQS11N  = M_F_DQS_DN<11>
  VSS(80)  = GND
  DQ(22)  = M_F_DQ<22>
  VSS(79)  = GND
  DQ(18)  = M_F_DQ<18>
  VSS(78)  = GND
  DQ(28)  = M_F_DQ<28>
  VSS(77)  = GND
  DQ(24)  = M_F_DQ<24>
  VSS(76)  = GND
  DQS12P  = M_F_DQS_DP<12>
  DQS12N  = M_F_DQS_DN<12>
  VSS(75)  = GND
  DQ(30)  = M_F_DQ<30>
  VSS(74)  = GND
  DQ(26)  = M_F_DQ<26>
  VSS(73)  = GND
  CB(4)  = M_F_ECC<4>
  VSS(72)  = GND
  CB(0)  = M_F_ECC<0>
  VSS(71)  = GND
  DQS17P  = M_F_DQS_DP<17>
  DQS17N  = M_F_DQS_DN<17>
  VSS(70)  = GND
  CB(6)  = M_F_ECC<6>
  VSS(69)  = GND
  CB(2)  = M_F_ECC<2>
  VSS(68)  = GND
  RESET_N  = M_DEF_RST_N
  VDD(25)  = PVDDQ_DEF
  CKE(0)  = M_F_CKE<2>
  VDD(24)  = PVDDQ_DEF
  ACT_N  = M_F_ACT_N
  BG(0)  = M_F_BG<0>
  VDD(23)  = PVDDQ_DEF
  A12  = M_F_MA<12>
  A9  = M_F_MA<9>
  VDD(22)  = PVDDQ_DEF
  A8  = M_F_MA<8>
  A6  = M_F_MA<6>
  VDD(21)  = PVDDQ_DEF
  A3  = M_F_MA<3>
  A1  = M_F_MA<1>
  VDD(20)  = PVDDQ_DEF
  CK0P  = M_F_CLK_DP<2>
  CK0N  = M_F_CLK_DN<2>
  VDD(19)  = PVDDQ_DEF
  VTT(1)  = PVTT_DEF
  EVENT_N  = FM_DIMM_EVENT_COD_N
  A0  = M_F_MA<0>
  VDD(18)  = PVDDQ_DEF
  BA(0)  = M_F_BA<0>
  A16_RAS_N  = M_F_MA<16>
  VDD(17)  = PVDDQ_DEF
  S0_N  = M_F_CS_N<4>
  VDD(16)  = PVDDQ_DEF
  A15_CAS_N  = M_F_MA<15>
  ODT(0)  = M_F_ODT<2>
  VDD(15)  = PVDDQ_DEF
  S1_N  = M_F_CS_N<5>
  VDD(14)  = PVDDQ_DEF
  ODT(1)  = M_F_ODT<3>
  VDD(13)  = PVDDQ_DEF
  S2_N_C(0)  = M_F_CS_N<6>
  VSS(67)  = GND
  DQ(36)  = M_F_DQ<36>
  VSS(66)  = GND
  DQ(32)  = M_F_DQ<32>
  VSS(65)  = GND
  DQS13P  = M_F_DQS_DP<13>
  DQS13N  = M_F_DQS_DN<13>
  VSS(64)  = GND
  DQ(38)  = M_F_DQ<38>
  VSS(63)  = GND
  DQ(34)  = M_F_DQ<34>
  VSS(62)  = GND
  DQ(44)  = M_F_DQ<44>
  VSS(61)  = GND
  DQ(40)  = M_F_DQ<40>
  VSS(60)  = GND
  DQS14P  = M_F_DQS_DP<14>
  DQS14N  = M_F_DQS_DN<14>
  VSS(59)  = GND
  DQ(46)  = M_F_DQ<46>
  VSS(58)  = GND
  DQ(42)  = M_F_DQ<42>
  VSS(57)  = GND
  DQ(52)  = M_F_DQ<52>
  VSS(56)  = GND
  DQ(48)  = M_F_DQ<48>
  VSS(55)  = GND
  DQS15P  = M_F_DQS_DP<15>
  DQS15N  = M_F_DQS_DN<15>
  VSS(54)  = GND
  DQ(54)  = M_F_DQ<54>
  VSS(53)  = GND
  DQ(50)  = M_F_DQ<50>
  VSS(52)  = GND
  DQ(60)  = M_F_DQ<60>
  VSS(51)  = GND
  DQ(56)  = M_F_DQ<56>
  VSS(50)  = GND
  DQS16P  = M_F_DQS_DP<16>
  DQS16N  = M_F_DQS_DN<16>
  VSS(49)  = GND
  DQ(62)  = M_F_DQ<62>
  VSS(48)  = GND
  DQ(58)  = M_F_DQ<58>
  VSS(47)  = GND
  SA(0)  = PVPP_DEF
  SA(1)  = GND
  SCL  = SMB_DDR_DEF_VPP_SCL
  VPP(4)  = PVPP_DEF
  VPP(3)  = PVPP_DEF
  RFU(2)  = TP_CH_F_DIMM_F1_RFU_2
  \12v\(0)  = P12V_NVDIMM_DEF
  VREFCA  = M_F_VREF
  VSS(46)  = GND
  DQ(5)  = M_F_DQ<5>
  VSS(45)  = GND
  DQ(1)  = M_F_DQ<1>
  VSS(44)  = GND
  DQS0N  = M_F_DQS_DN<0>
  DQS0P  = M_F_DQS_DP<0>
  VSS(43)  = GND
  DQ(7)  = M_F_DQ<7>
  VSS(42)  = GND
  DQ(3)  = M_F_DQ<3>
  VSS(41)  = GND
  DQ(13)  = M_F_DQ<13>
  VSS(40)  = GND
  DQ(9)  = M_F_DQ<9>
  VSS(39)  = GND
  DQS1N  = M_F_DQS_DN<1>
  DQS1P  = M_F_DQS_DP<1>
  VSS(38)  = GND
  DQ(15)  = M_F_DQ<15>
  VSS(37)  = GND
  DQ(11)  = M_F_DQ<11>
  VSS(36)  = GND
  DQ(21)  = M_F_DQ<21>
  VSS(35)  = GND
  DQ(17)  = M_F_DQ<17>
  VSS(34)  = GND
  DQS2N  = M_F_DQS_DN<2>
  DQS2P  = M_F_DQS_DP<2>
  VSS(33)  = GND
  DQ(23)  = M_F_DQ<23>
  VSS(32)  = GND
  DQ(19)  = M_F_DQ<19>
  VSS(31)  = GND
  DQ(29)  = M_F_DQ<29>
  VSS(30)  = GND
  DQ(25)  = M_F_DQ<25>
  VSS(29)  = GND
  DQS3N  = M_F_DQS_DN<3>
  DQS3P  = M_F_DQS_DP<3>
  VSS(28)  = GND
  DQ(31)  = M_F_DQ<31>
  VSS(27)  = GND
  DQ(27)  = M_F_DQ<27>
  VSS(26)  = GND
  CB(5)  = M_F_ECC<5>
  VSS(25)  = GND
  CB(1)  = M_F_ECC<1>
  VSS(24)  = GND
  DQS8N  = M_F_DQS_DN<8>
  DQS8P  = M_F_DQS_DP<8>
  VSS(23)  = GND
  CB(7)  = M_F_ECC<7>
  VSS(22)  = GND
  CB(3)  = M_F_ECC<3>
  VSS(21)  = GND
  CKE(1)  = M_F_CKE<3>
  VDD(12)  = PVDDQ_DEF
  RFU(0)  = TP_CH_F_DIMM_F1_RFU_0
  VDD(11)  = PVDDQ_DEF
  BG(1)  = M_F_BG<1>
  ALERT_N  = M_F_ALERT_N
  VDD(10)  = PVDDQ_DEF
  A11  = M_F_MA<11>
  A7  = M_F_MA<7>
  VDD(9)  = PVDDQ_DEF
  A5  = M_F_MA<5>
  A4  = M_F_MA<4>
  VDD(8)  = PVDDQ_DEF
  A2  = M_F_MA<2>
  VDD(7)  = PVDDQ_DEF
  CK1P  = M_F_CLK_DP<3>
  CK1N  = M_F_CLK_DN<3>
  VDD(6)  = PVDDQ_DEF
  VTT(0)  = PVTT_DEF
  PAR  = M_F_PAR
  VDD(5)  = PVDDQ_DEF
  BA(1)  = M_F_BA<1>
  A10  = M_F_MA<10>
  VDD(4)  = PVDDQ_DEF
  RFU(1)  = TP_CH_F_DIMM_F1_RFU_1
  A14_WE_N  = M_F_MA<14>
  VDD(3)  = PVDDQ_DEF
  SAVE_N_NC  = FM_ADR_COMPLETE_DEF_N
  VDD(2)  = PVDDQ_DEF
  A13  = M_F_MA<13>
  VDD(1)  = PVDDQ_DEF
  A17  = M_F_MA<17>
  C(2)  = M_F_C<2>
  VDD(0)  = PVDDQ_DEF
  S3_N_C(1)  = M_F_CS_N<7>
  SA(2)  = PVPP_DEF
  VSS(20)  = GND
  DQ(37)  = M_F_DQ<37>
  VSS(19)  = GND
  DQ(33)  = M_F_DQ<33>
  VSS(18)  = GND
  DQS4N  = M_F_DQS_DN<4>
  DQS4P  = M_F_DQS_DP<4>
  VSS(17)  = GND
  DQ(39)  = M_F_DQ<39>
  VSS(16)  = GND
  DQ(35)  = M_F_DQ<35>
  VSS(15)  = GND
  DQ(45)  = M_F_DQ<45>
  VSS(14)  = GND
  DQ(41)  = M_F_DQ<41>
  VSS(13)  = GND
  DQS5N  = M_F_DQS_DN<5>
  DQS5P  = M_F_DQS_DP<5>
  VSS(12)  = GND
  DQ(47)  = M_F_DQ<47>
  VSS(11)  = GND
  DQ(43)  = M_F_DQ<43>
  VSS(10)  = GND
  DQ(53)  = M_F_DQ<53>
  VSS(9)  = GND
  DQ(49)  = M_F_DQ<49>
  VSS(8)  = GND
  DQS6N  = M_F_DQS_DN<6>
  DQS6P  = M_F_DQS_DP<6>
  VSS(7)  = GND
  DQ(55)  = M_F_DQ<55>
  VSS(6)  = GND
  DQ(51)  = M_F_DQ<51>
  VSS(5)  = GND
  DQ(61)  = M_F_DQ<61>
  VSS(4)  = GND
  DQ(57)  = M_F_DQ<57>
  VSS(3)  = GND
  DQS7N  = M_F_DQS_DN<7>
  DQS7P  = M_F_DQS_DP<7>
  VSS(2)  = GND
  DQ(63)  = M_F_DQ<63>
  VSS(1)  = GND
  DQ(59)  = M_F_DQ<59>
  VSS(0)  = GND
  VDDSPD  = PVPP_DEF
  SDA  = SMB_DDR_DEF_VPP_SDA
  VPP(1)  = PVPP_DEF
  VPP(0)  = PVPP_DEF
  VPP(2)  = PVPP_DEF

(kicad_pcb
	(version 20260206)
	(generator "pcbnew")
	(generator_version "10.0")
	(general
		(thickness 1.6)
		(legacy_teardrops no)
	)
	(paper "A4")
	(title_block
		(title "Wiwynn_Tioga_Pass_MB.brd")
		(comment 1 "Tioga Pass / footprint 4129 of 4770 (J6L1), pads 202-249 of 291")
	)
	(layers
		(0 "F.Cu" signal "TOP")
		(4 "In1.Cu" signal "L2GND")
		(6 "In2.Cu" signal "L3")
		(8 "In3.Cu" signal "L4GND")
		(10 "In4.Cu" signal "L5")
		(12 "In5.Cu" signal "L6GND")
		(14 "In6.Cu" signal "L7VCC")
		(16 "In7.Cu" signal "L8VCC")
		(18 "In8.Cu" signal "L9GND")
		(20 "In9.Cu" signal "L10")
		(22 "In10.Cu" signal "L11GND")
		(24 "In11.Cu" signal "L12")
		(26 "In12.Cu" signal "L13GND")
		(2 "B.Cu" signal "BOTTOM")
		(9 "F.Adhes" user "F.Adhesive")
		(11 "B.Adhes" user "B.Adhesive")
		(13 "F.Paste" user "Package Geometry/Pastemask Top")
		(15 "B.Paste" user "Package Geometry/Pastemask Bottom")
		(5 "F.SilkS" user "Ref Des/Silkscreen Top")
		(7 "B.SilkS" user "Ref Des/Silkscreen Bottom")
		(1 "F.Mask" user "Board Geometry/Soldermask Top")
		(3 "B.Mask" user "Board Geometry/Soldermask Bottom")
		(17 "Dwgs.User" user "User.Drawings")
		(19 "Cmts.User" user "User.Comments")
		(21 "Eco1.User" user "User.Eco1")
		(23 "Eco2.User" user "User.Eco2")
		(25 "Edge.Cuts" user "Board Geometry/Outline")
		(27 "Margin" user)
		(31 "F.CrtYd" user "Package Geometry/Place Bound Top")
		(29 "B.CrtYd" user "Package Geometry/Place Bound Bottom")
		(35 "F.Fab" user "Ref Des/Assembly Top")
		(33 "B.Fab" user "Ref Des/Assembly Bottom")
	)
	(footprint ""
		(layer "B.Cu")
		(at 194.700398 -152.078436 90)
		(property "Reference" "J6L1"
			(at 2.200148 37.96411 0)
			(unlocked yes)
			(layer "B.SilkS")
			(effects
				(font
					(size 0.7874 0.5842)
					(thickness 0.1524)
				)
				(justify left mirror)
			)
		)
		(property "Value" ""
			(at 0 0 90)
			(layer "B.Fab")
			(effects
				(font
					(size 1.27 1.27)
				)
				(justify mirror)
			)
		)
		(duplicate_pad_numbers_are_jumpers no)
		(pad "199" smd rect
			(at -4.59994 45.900086 270)
			(size 1.8034 0.508)
			(layers "B.Cu" "B.Mask" "B.Paste")
			(net "M_F_ECC<7>")
		)
		(pad "200" smd rect
			(at -4.59994 46.74997 270)
			(size 1.8034 0.508)
			(layers "B.Cu" "B.Mask" "B.Paste")
			(net "GND")
		)
		(pad "201" smd rect
			(at -4.59994 47.600108 270)
			(size 1.8034 0.508)
			(layers "B.Cu" "B.Mask" "B.Paste")
			(net "M_F_ECC<3>")
		)
		(pad "202" smd rect
			(at -4.59994 48.449992 270)
			(size 1.8034 0.508)
			(layers "B.Cu" "B.Mask" "B.Paste")
			(net "GND")
		)
		(pad "203" smd rect
			(at -4.59994 49.299876 270)
			(size 1.8034 0.508)
			(layers "B.Cu" "B.Mask" "B.Paste")
			(net "M_F_CKE<3>")
		)
		(pad "204" smd rect
			(at -4.59994 50.150014 270)
			(size 1.8034 0.508)
			(layers "B.Cu" "B.Mask" "B.Paste")
			(net "PVDDQ_DEF")
		)
		(pad "205" smd rect
			(at -4.59994 50.999898 270)
			(size 1.8034 0.508)
			(layers "B.Cu" "B.Mask" "B.Paste")
			(net "TP_CH_F_DIMM_F1_RFU_0")
		)
		(pad "206" smd rect
			(at -4.59994 51.850036 270)
			(size 1.8034 0.508)
			(layers "B.Cu" "B.Mask" "B.Paste")
			(net "PVDDQ_DEF")
		)
		(pad "207" smd rect
			(at -4.59994 52.69992 270)
			(size 1.8034 0.508)
			(layers "B.Cu" "B.Mask" "B.Paste")
			(net "M_F_BG<1>")
		)
		(pad "208" smd rect
			(at -4.59994 53.550058 270)
			(size 1.8034 0.508)
			(layers "B.Cu" "B.Mask" "B.Paste")
			(net "M_F_ALERT_N")
		)
		(pad "209" smd rect
			(at -4.59994 54.399942 270)
			(size 1.8034 0.508)
			(layers "B.Cu" "B.Mask" "B.Paste")
			(net "PVDDQ_DEF")
		)
		(pad "210" smd rect
			(at -4.59994 55.25008 270)
			(size 1.8034 0.508)
			(layers "B.Cu" "B.Mask" "B.Paste")
			(net "M_F_MA<11>")
		)
		(pad "211" smd rect
			(at -4.59994 56.099964 270)
			(size 1.8034 0.508)
			(layers "B.Cu" "B.Mask" "B.Paste")
			(net "M_F_MA<7>")
		)
		(pad "212" smd rect
			(at -4.59994 56.950102 270)
			(size 1.8034 0.508)
			(layers "B.Cu" "B.Mask" "B.Paste")
			(net "PVDDQ_DEF")
		)
		(pad "213" smd rect
			(at -4.59994 57.799986 270)
			(size 1.8034 0.508)
			(layers "B.Cu" "B.Mask" "B.Paste")
			(net "M_F_MA<5>")
		)
		(pad "214" smd rect
			(at -4.59994 58.650124 270)
			(size 1.8034 0.508)
			(layers "B.Cu" "B.Mask" "B.Paste")
			(net "M_F_MA<4>")
		)
		(pad "215" smd rect
			(at -4.59994 59.500008 270)
			(size 1.8034 0.508)
			(layers "B.Cu" "B.Mask" "B.Paste")
			(net "PVDDQ_DEF")
		)
		(pad "216" smd rect
			(at -4.59994 60.349892 270)
			(size 1.8034 0.508)
			(layers "B.Cu" "B.Mask" "B.Paste")
			(net "M_F_MA<2>")
		)
		(pad "217" smd rect
			(at -4.59994 61.20003 270)
			(size 1.8034 0.508)
			(layers "B.Cu" "B.Mask" "B.Paste")
			(net "PVDDQ_DEF")
		)
		(pad "218" smd rect
			(at -4.59994 62.049914 270)
			(size 1.8034 0.508)
			(layers "B.Cu" "B.Mask" "B.Paste")
			(net "M_F_CLK_DP<3>")
		)
		(pad "219" smd rect
			(at -4.59994 62.900052 270)
			(size 1.8034 0.508)
			(layers "B.Cu" "B.Mask" "B.Paste")
			(net "M_F_CLK_DN<3>")
		)
		(pad "220" smd rect
			(at -4.59994 63.749936 270)
			(size 1.8034 0.508)
			(layers "B.Cu" "B.Mask" "B.Paste")
			(net "PVDDQ_DEF")
		)
		(pad "221" smd rect
			(at -4.59994 64.600074 270)
			(size 1.8034 0.508)
			(layers "B.Cu" "B.Mask" "B.Paste")
			(net "PVTT_DEF")
		)
		(pad "222" smd rect
			(at -4.59994 70.550024 270)
			(size 1.8034 0.508)
			(layers "B.Cu" "B.Mask" "B.Paste")
			(net "M_F_PAR")
		)
		(pad "223" smd rect
			(at -4.59994 71.399908 270)
			(size 1.8034 0.508)
			(layers "B.Cu" "B.Mask" "B.Paste")
			(net "PVDDQ_DEF")
		)
		(pad "224" smd rect
			(at -4.59994 72.250046 270)
			(size 1.8034 0.508)
			(layers "B.Cu" "B.Mask" "B.Paste")
			(net "M_F_BA<1>")
		)
		(pad "225" smd rect
			(at -4.59994 73.09993 270)
			(size 1.8034 0.508)
			(layers "B.Cu" "B.Mask" "B.Paste")
			(net "M_F_MA<10>")
		)
		(pad "226" smd rect
			(at -4.59994 73.950068 270)
			(size 1.8034 0.508)
			(layers "B.Cu" "B.Mask" "B.Paste")
			(net "PVDDQ_DEF")
		)
		(pad "227" smd rect
			(at -4.59994 74.799952 270)
			(size 1.8034 0.508)
			(layers "B.Cu" "B.Mask" "B.Paste")
			(net "TP_CH_F_DIMM_F1_RFU_1")
		)
		(pad "228" smd rect
			(at -4.59994 75.65009 270)
			(size 1.8034 0.508)
			(layers "B.Cu" "B.Mask" "B.Paste")
			(net "M_F_MA<14>")
		)
		(pad "229" smd rect
			(at -4.59994 76.499974 270)
			(size 1.8034 0.508)
			(layers "B.Cu" "B.Mask" "B.Paste")
			(net "PVDDQ_DEF")
		)
		(pad "230" smd rect
			(at -4.59994 77.350112 270)
			(size 1.8034 0.508)
			(layers "B.Cu" "B.Mask" "B.Paste")
			(net "FM_ADR_COMPLETE_DEF_N")
		)
		(pad "231" smd rect
			(at -4.59994 78.199996 270)
			(size 1.8034 0.508)
			(layers "B.Cu" "B.Mask" "B.Paste")
			(net "PVDDQ_DEF")
		)
		(pad "232" smd rect
			(at -4.59994 79.04988 270)
			(size 1.8034 0.508)
			(layers "B.Cu" "B.Mask" "B.Paste")
			(net "M_F_MA<13>")
		)
		(pad "233" smd rect
			(at -4.59994 79.900018 270)
			(size 1.8034 0.508)
			(layers "B.Cu" "B.Mask" "B.Paste")
			(net "PVDDQ_DEF")
		)
		(pad "234" smd rect
			(at -4.59994 80.749902 270)
			(size 1.8034 0.508)
			(layers "B.Cu" "B.Mask" "B.Paste")
			(net "M_F_MA<17>")
		)
		(pad "235" smd rect
			(at -4.59994 81.60004 270)
			(size 1.8034 0.508)
			(layers "B.Cu" "B.Mask" "B.Paste")
			(net "M_F_C<2>")
		)
		(pad "236" smd rect
			(at -4.59994 82.449924 270)
			(size 1.8034 0.508)
			(layers "B.Cu" "B.Mask" "B.Paste")
			(net "PVDDQ_DEF")
		)
		(pad "237" smd rect
			(at -4.59994 83.300062 270)
			(size 1.8034 0.508)
			(layers "B.Cu" "B.Mask" "B.Paste")
			(net "M_F_CS_N<7>")
		)
		(pad "238" smd rect
			(at -4.59994 84.149946 270)
			(size 1.8034 0.508)
			(layers "B.Cu" "B.Mask" "B.Paste")
			(net "PVPP_DEF")
		)
		(pad "239" smd rect
			(at -4.59994 85.000084 270)
			(size 1.8034 0.508)
			(layers "B.Cu" "B.Mask" "B.Paste")
			(net "GND")
		)
		(pad "240" smd rect
			(at -4.59994 85.849968 270)
			(size 1.8034 0.508)
			(layers "B.Cu" "B.Mask" "B.Paste")
			(net "M_F_DQ<37>")
		)
		(pad "241" smd rect
			(at -4.59994 86.700106 270)
			(size 1.8034 0.508)
			(layers "B.Cu" "B.Mask" "B.Paste")
			(net "GND")
		)
		(pad "242" smd rect
			(at -4.59994 87.54999 270)
			(size 1.8034 0.508)
			(layers "B.Cu" "B.Mask" "B.Paste")
			(net "M_F_DQ<33>")
		)
		(pad "243" smd rect
			(at -4.59994 88.399874 270)
			(size 1.8034 0.508)
			(layers "B.Cu" "B.Mask" "B.Paste")
			(net "GND")
		)
		(pad "244" smd rect
			(at -4.59994 89.250012 270)
			(size 1.8034 0.508)
			(layers "B.Cu" "B.Mask" "B.Paste")
			(net "M_F_DQS_DN<4>")
		)
		(pad "245" smd rect
			(at -4.59994 90.099896 270)
			(size 1.8034 0.508)
			(layers "B.Cu" "B.Mask" "B.Paste")
			(net "M_F_DQS_DP<4>")
		)
		(pad "246" smd rect
			(at -4.59994 90.950034 270)
			(size 1.8034 0.508)
			(layers "B.Cu" "B.Mask" "B.Paste")
			(net "GND")
		)
	)
)
